FILE_TYPE = MACRO_DRAWING;
SET COLOR_WIRE YELLOW;
SET COLOR_PROP ORANGE;
SET COLOR_DOT WHITE;
SET COLOR_ARC YELLOW;
SET COLOR_BODY GREEN;
SET COLOR_NOTE PURPLE;
SET PROP_DISPLAY VALUE;
SET PAGE_NUMBER P129;
FORCEADD UNIVERSAL_GND..1
(-7475 300);
FORCEPROP 3 LASTPIN (-7475 350) SIG_NAME GND\g
J 0
(-7465 360);
DISPLAY 0.659574 (-7465 360);
PAINT MONO (-7465 360);
DISPLAY INVISIBLE (-7465 360);
FORCEPROP 2 LAST CDS_LIB logical_power
J 0
(-7475 300);
PAINT MONO (-7475 300);
DISPLAY INVISIBLE (-7475 300);
FORCEPROP 1 LAST HDL_POWER GND
J 1
(-7450 225);
DISPLAY 0.872340 (-7450 225);
PAINT GREEN (-7450 225);
DISPLAY INVISIBLE (-7450 225);
FORCEPROP 1 LAST PATH I100
J 0
(-7400 300);
DISPLAY 0.872340 (-7400 300);
PAINT AQUA (-7400 300);
DISPLAY INVISIBLE (-7400 300);
FORCEADD Q_CAP..1
R 2
(-7475 600);
FORCEPROP 1 LAST PART_NUMBER CH5104KEB02
J 2
(-7525 450);
DISPLAY 0.510638 (-7525 450);
DISPLAY INVISIBLE (-7525 450);
FORCEPROP 1 LAST PACK_TYPE C0402
J 2
(-7525 400);
DISPLAY 0.510638 (-7525 400);
FORCEPROP 1 LAST VALUE 1UF
J 2
(-7525 650);
DISPLAY 0.510638 (-7525 650);
FORCEPROP 1 LAST VOLTAGE 25V
J 2
(-7525 600);
DISPLAY 0.510638 (-7525 600);
FORCEPROP 1 LAST TOLERANCE 10%
J 2
(-7525 550);
DISPLAY 0.510638 (-7525 550);
FORCEPROP 1 LAST MATERIAL EMPTY
J 2
(-7525 500);
DISPLAY 0.510638 (-7525 500);
FORCEPROP 1 LAST $LOCATION C621
J 2
(-7525 700);
DISPLAY 0.978723 (-7525 700);
FORCEPROP 1 LASTPIN (-7475 700) $PN 1
J 2
(-7485 680);
DISPLAY 0.787234 (-7485 680);
FORCEPROP 1 LASTPIN (-7475 500) $PN 2
J 2
(-7485 480);
DISPLAY 0.787234 (-7485 480);
FORCEPROP 2 LAST CDS_LIB pure_quanta
J 0
(-7475 600);
PAINT MONO (-7475 600);
DISPLAY INVISIBLE (-7475 600);
FORCEPROP 1 LAST PATH I102
J 2
(-7525 750);
DISPLAY 0.978723 (-7525 750);
PAINT WHITE (-7525 750);
DISPLAY INVISIBLE (-7525 750);
FORCEPROP 2 LAST CDS_LOCATION C621
J 0
(-7525 800);
DISPLAY 1.021277 (-7525 800);
DISPLAY INVISIBLE (-7525 800);
FORCEPROP 2 LAST $SEC 1
J 0
(-7525 800);
DISPLAY 0.680851 (-7525 800);
PAINT MONO (-7525 800);
DISPLAY INVISIBLE (-7525 800);
FORCEPROP 2 LAST CDS_SEC 1
J 0
(-7525 800);
DISPLAY 1.021277 (-7525 800);
DISPLAY INVISIBLE (-7525 800);
FORCEADD Q_RES..2
(-7350 5150);
FORCEPROP 1 LAST PART_NUMBER CS31002FB08
J 0
(-7310 5000);
DISPLAY 0.510638 (-7310 5000);
DISPLAY INVISIBLE (-7310 5000);
FORCEPROP 1 LAST WATTAGE 1/16W
J 0
(-7310 5100);
DISPLAY 0.510638 (-7310 5100);
FORCEPROP 1 LAST VALUE 10K
J 0
(-7305 5200);
DISPLAY 0.510638 (-7305 5200);
FORCEPROP 1 LAST MATERIAL EMPTY
J 0
(-7310 5050);
DISPLAY 0.510638 (-7310 5050);
PAINT RED (-7310 5050);
FORCEPROP 1 LAST TOLERANCE 1%
J 0
(-7305 5150);
DISPLAY 0.510638 (-7305 5150);
FORCEPROP 1 LAST PACK_TYPE 0402LF
J 0
(-7310 4950);
DISPLAY 0.510638 (-7310 4950);
FORCEPROP 1 LAST $LOCATION R706
J 0
(-7305 5250);
DISPLAY 1.021277 (-7305 5250);
FORCEPROP 1 LASTPIN (-7350 5250) $PN 1
J 0
(-7345 5212);
DISPLAY 0.787234 (-7345 5212);
FORCEPROP 1 LASTPIN (-7350 5050) $PN 2
J 0
(-7345 5060);
DISPLAY 0.787234 (-7345 5060);
FORCEPROP 2 LAST CDS_LIB pure_quanta
J 0
(-7350 5150);
PAINT MONO (-7350 5150);
DISPLAY INVISIBLE (-7350 5150);
FORCEPROP 1 LAST PATH I103
J 0
(-7300 5325);
DISPLAY 0.978723 (-7300 5325);
PAINT WHITE (-7300 5325);
DISPLAY INVISIBLE (-7300 5325);
FORCEPROP 2 LAST CDS_LOCATION R706
J 0
(-7300 5375);
DISPLAY 1.021277 (-7300 5375);
DISPLAY INVISIBLE (-7300 5375);
FORCEPROP 2 LAST $SEC 1
J 0
(-7300 5375);
DISPLAY 0.680851 (-7300 5375);
PAINT MONO (-7300 5375);
DISPLAY INVISIBLE (-7300 5375);
FORCEPROP 2 LAST CDS_SEC 1
J 0
(-7300 5375);
DISPLAY 1.021277 (-7300 5375);
DISPLAY INVISIBLE (-7300 5375);
FORCEADD Q_RES..2
(-7350 3625);
FORCEPROP 1 LAST PART_NUMBER CS31002FB08
J 0
(-7310 3475);
DISPLAY 0.510638 (-7310 3475);
DISPLAY INVISIBLE (-7310 3475);
FORCEPROP 1 LAST MATERIAL EMPTY
J 0
(-7310 3525);
DISPLAY 0.510638 (-7310 3525);
PAINT RED (-7310 3525);
FORCEPROP 1 LAST WATTAGE 1/16W
J 0
(-7310 3575);
DISPLAY 0.510638 (-7310 3575);
FORCEPROP 1 LAST VALUE 10K
J 0
(-7305 3675);
DISPLAY 0.510638 (-7305 3675);
FORCEPROP 1 LAST PACK_TYPE 0402LF
J 0
(-7310 3425);
DISPLAY 0.510638 (-7310 3425);
FORCEPROP 1 LAST TOLERANCE 1%
J 0
(-7305 3625);
DISPLAY 0.510638 (-7305 3625);
FORCEPROP 1 LAST $LOCATION R707
J 0
(-7305 3725);
DISPLAY 1.021277 (-7305 3725);
FORCEPROP 1 LASTPIN (-7350 3725) $PN 1
J 0
(-7345 3687);
DISPLAY 0.787234 (-7345 3687);
FORCEPROP 1 LASTPIN (-7350 3525) $PN 2
J 0
(-7345 3535);
DISPLAY 0.787234 (-7345 3535);
FORCEPROP 2 LAST CDS_LIB pure_quanta
J 0
(-7350 3625);
PAINT MONO (-7350 3625);
DISPLAY INVISIBLE (-7350 3625);
FORCEPROP 1 LAST PATH I106
J 0
(-7300 3800);
DISPLAY 0.978723 (-7300 3800);
PAINT WHITE (-7300 3800);
DISPLAY INVISIBLE (-7300 3800);
FORCEPROP 2 LAST CDS_LOCATION R707
J 0
(-7300 3850);
DISPLAY 1.021277 (-7300 3850);
DISPLAY INVISIBLE (-7300 3850);
FORCEPROP 2 LAST $SEC 1
J 0
(-7300 3850);
DISPLAY 0.680851 (-7300 3850);
PAINT MONO (-7300 3850);
DISPLAY INVISIBLE (-7300 3850);
FORCEPROP 2 LAST CDS_SEC 1
J 0
(-7300 3850);
DISPLAY 1.021277 (-7300 3850);
DISPLAY INVISIBLE (-7300 3850);
FORCEADD Q_RES..2
(-7350 2125);
FORCEPROP 1 LAST PART_NUMBER CS31002FB08
J 0
(-7310 1975);
DISPLAY 0.510638 (-7310 1975);
DISPLAY INVISIBLE (-7310 1975);
FORCEPROP 1 LAST WATTAGE 1/16W
J 0
(-7310 2075);
DISPLAY 0.510638 (-7310 2075);
FORCEPROP 1 LAST VALUE 10K
J 0
(-7305 2175);
DISPLAY 0.510638 (-7305 2175);
FORCEPROP 1 LAST TOLERANCE 1%
J 0
(-7305 2125);
DISPLAY 0.510638 (-7305 2125);
FORCEPROP 1 LAST MATERIAL EMPTY
J 0
(-7310 2025);
DISPLAY 0.510638 (-7310 2025);
PAINT RED (-7310 2025);
FORCEPROP 1 LAST PACK_TYPE 0402LF
J 0
(-7310 1925);
DISPLAY 0.510638 (-7310 1925);
FORCEPROP 1 LAST $LOCATION R708
J 0
(-7305 2225);
DISPLAY 1.021277 (-7305 2225);
FORCEPROP 1 LASTPIN (-7350 2225) $PN 1
J 0
(-7345 2187);
DISPLAY 0.787234 (-7345 2187);
FORCEPROP 1 LASTPIN (-7350 2025) $PN 2
J 0
(-7345 2035);
DISPLAY 0.787234 (-7345 2035);
FORCEPROP 2 LAST CDS_LIB pure_quanta
J 0
(-7350 2125);
PAINT MONO (-7350 2125);
DISPLAY INVISIBLE (-7350 2125);
FORCEPROP 1 LAST PATH I109
J 0
(-7300 2300);
DISPLAY 0.978723 (-7300 2300);
PAINT WHITE (-7300 2300);
DISPLAY INVISIBLE (-7300 2300);
FORCEPROP 2 LAST CDS_LOCATION R708
J 0
(-7300 2350);
DISPLAY 1.021277 (-7300 2350);
DISPLAY INVISIBLE (-7300 2350);
FORCEPROP 2 LAST $SEC 1
J 0
(-7300 2350);
DISPLAY 0.680851 (-7300 2350);
PAINT MONO (-7300 2350);
DISPLAY INVISIBLE (-7300 2350);
FORCEPROP 2 LAST CDS_SEC 1
J 0
(-7300 2350);
DISPLAY 1.021277 (-7300 2350);
DISPLAY INVISIBLE (-7300 2350);
FORCEADD Q_RES..2
(-7350 600);
FORCEPROP 1 LAST PART_NUMBER CS31002FB08
J 0
(-7310 450);
DISPLAY 0.510638 (-7310 450);
DISPLAY INVISIBLE (-7310 450);
FORCEPROP 1 LAST MATERIAL EMPTY
J 0
(-7310 500);
DISPLAY 0.510638 (-7310 500);
PAINT RED (-7310 500);
FORCEPROP 1 LAST TOLERANCE 1%
J 0
(-7305 600);
DISPLAY 0.510638 (-7305 600);
FORCEPROP 1 LAST PACK_TYPE 0402LF
J 0
(-7310 400);
DISPLAY 0.510638 (-7310 400);
FORCEPROP 1 LAST VALUE 10K
J 0
(-7305 650);
DISPLAY 0.510638 (-7305 650);
FORCEPROP 1 LAST WATTAGE 1/16W
J 0
(-7310 550);
DISPLAY 0.510638 (-7310 550);
FORCEPROP 1 LAST $LOCATION R705
J 0
(-7305 700);
DISPLAY 1.021277 (-7305 700);
FORCEPROP 1 LASTPIN (-7350 700) $PN 1
J 0
(-7345 662);
DISPLAY 0.787234 (-7345 662);
FORCEPROP 1 LASTPIN (-7350 500) $PN 2
J 0
(-7345 510);
DISPLAY 0.787234 (-7345 510);
FORCEPROP 2 LAST CDS_LIB pure_quanta
J 0
(-7350 600);
PAINT MONO (-7350 600);
DISPLAY INVISIBLE (-7350 600);
FORCEPROP 1 LAST PATH I112
J 0
(-7300 775);
DISPLAY 0.978723 (-7300 775);
PAINT WHITE (-7300 775);
DISPLAY INVISIBLE (-7300 775);
FORCEPROP 2 LAST CDS_LOCATION R705
J 0
(-7300 825);
DISPLAY 1.021277 (-7300 825);
DISPLAY INVISIBLE (-7300 825);
FORCEPROP 2 LAST $SEC 1
J 0
(-7300 825);
DISPLAY 0.680851 (-7300 825);
PAINT MONO (-7300 825);
DISPLAY INVISIBLE (-7300 825);
FORCEPROP 2 LAST CDS_SEC 1
J 0
(-7300 825);
DISPLAY 1.021277 (-7300 825);
DISPLAY INVISIBLE (-7300 825);
FORCEADD Q_RES..2
(-2725 5775);
FORCEPROP 1 LAST PART_NUMBER CS21002FB06
J 0
(-2685 5650);
DISPLAY 0.638298 (-2685 5650);
DISPLAY INVISIBLE (-2685 5650);
FORCEPROP 1 LAST PACK_TYPE 0402LF
J 0
(-2685 5600);
DISPLAY 0.638298 (-2685 5600);
FORCEPROP 1 LAST TOLERANCE 1%
J 0
(-2680 5800);
DISPLAY 0.638298 (-2680 5800);
FORCEPROP 1 LAST VALUE 1K
J 0
(-2680 5850);
DISPLAY 0.638298 (-2680 5850);
FORCEPROP 1 LAST WATTAGE 1/16W
J 0
(-2685 5750);
DISPLAY 0.638298 (-2685 5750);
FORCEPROP 1 LAST MATERIAL CHIP
J 0
(-2685 5700);
DISPLAY 0.638298 (-2685 5700);
FORCEPROP 1 LAST $LOCATION R840
J 0
(-2680 5900);
DISPLAY 0.978723 (-2680 5900);
FORCEPROP 1 LASTPIN (-2725 5875) $PN 1
J 0
(-2720 5837);
DISPLAY 0.787234 (-2720 5837);
FORCEPROP 1 LASTPIN (-2725 5675) $PN 2
J 0
(-2720 5685);
DISPLAY 0.787234 (-2720 5685);
FORCEPROP 2 LAST CDS_LIB pure_quanta
J 0
(-2725 5775);
PAINT MONO (-2725 5775);
DISPLAY INVISIBLE (-2725 5775);
FORCEPROP 1 LAST PATH I119
J 0
(-2675 5950);
DISPLAY 0.978723 (-2675 5950);
PAINT WHITE (-2675 5950);
DISPLAY INVISIBLE (-2675 5950);
FORCEPROP 1 LAST $LOCATION R840
J 0
(-2675 6000);
DISPLAY 1.021277 (-2675 6000);
DISPLAY INVISIBLE (-2675 6000);
FORCEPROP 2 LAST CDS_LOCATION R840
J 0
(-2675 6000);
DISPLAY 1.021277 (-2675 6000);
DISPLAY INVISIBLE (-2675 6000);
FORCEPROP 2 LAST $SEC 1
J 0
(-2675 6000);
DISPLAY 0.680851 (-2675 6000);
PAINT MONO (-2675 6000);
DISPLAY INVISIBLE (-2675 6000);
FORCEPROP 2 LAST CDS_SEC 1
J 0
(-2675 6000);
DISPLAY 1.021277 (-2675 6000);
DISPLAY INVISIBLE (-2675 6000);
FORCEADD UNIVERSAL_POWER..1
(-2725 6025);
FORCEPROP 3 LASTPIN (-2725 5975) SIG_NAME PVCCD_HV_CPU0\g
J 0
(-2715 5985);
DISPLAY 0.659574 (-2715 5985);
PAINT MONO (-2715 5985);
DISPLAY INVISIBLE (-2715 5985);
FORCEPROP 1 LAST HDL_POWER PVCCD_HV_CPU0
J 1
(-2725 6075);
DISPLAY 0.872340 (-2725 6075);
PAINT GREEN (-2725 6075);
FORCEPROP 2 LAST CDS_LIB logical_power
J 0
(-2725 6025);
PAINT MONO (-2725 6025);
DISPLAY INVISIBLE (-2725 6025);
FORCEPROP 1 LAST PATH I120
J 0
(-2675 6050);
DISPLAY 0.872340 (-2675 6050);
PAINT AQUA (-2675 6050);
DISPLAY INVISIBLE (-2675 6050);
FORCEADD Q_RES..2
(-2725 4250);
FORCEPROP 1 LAST PART_NUMBER CS21002FB06
J 0
(-2685 4125);
DISPLAY 0.638298 (-2685 4125);
DISPLAY INVISIBLE (-2685 4125);
FORCEPROP 1 LAST TOLERANCE 1%
J 0
(-2680 4275);
DISPLAY 0.638298 (-2680 4275);
FORCEPROP 1 LAST VALUE 1K
J 0
(-2680 4325);
DISPLAY 0.638298 (-2680 4325);
FORCEPROP 1 LAST PACK_TYPE 0402LF
J 0
(-2685 4075);
DISPLAY 0.638298 (-2685 4075);
FORCEPROP 1 LAST WATTAGE 1/16W
J 0
(-2685 4225);
DISPLAY 0.638298 (-2685 4225);
FORCEPROP 1 LAST MATERIAL CHIP
J 0
(-2685 4175);
DISPLAY 0.638298 (-2685 4175);
FORCEPROP 1 LAST $LOCATION R841
J 0
(-2680 4375);
DISPLAY 0.978723 (-2680 4375);
FORCEPROP 1 LASTPIN (-2725 4350) $PN 1
J 0
(-2720 4312);
DISPLAY 0.787234 (-2720 4312);
FORCEPROP 1 LASTPIN (-2725 4150) $PN 2
J 0
(-2720 4160);
DISPLAY 0.787234 (-2720 4160);
FORCEPROP 2 LAST CDS_LIB pure_quanta
J 0
(-2725 4250);
PAINT MONO (-2725 4250);
DISPLAY INVISIBLE (-2725 4250);
FORCEPROP 1 LAST PATH I121
J 0
(-2675 4425);
DISPLAY 0.978723 (-2675 4425);
PAINT WHITE (-2675 4425);
DISPLAY INVISIBLE (-2675 4425);
FORCEPROP 1 LAST $LOCATION R841
J 0
(-2675 4475);
DISPLAY 1.021277 (-2675 4475);
DISPLAY INVISIBLE (-2675 4475);
FORCEPROP 2 LAST CDS_LOCATION R841
J 0
(-2675 4475);
DISPLAY 1.021277 (-2675 4475);
DISPLAY INVISIBLE (-2675 4475);
FORCEPROP 2 LAST $SEC 1
J 0
(-2675 4475);
DISPLAY 0.680851 (-2675 4475);
PAINT MONO (-2675 4475);
DISPLAY INVISIBLE (-2675 4475);
FORCEPROP 2 LAST CDS_SEC 1
J 0
(-2675 4475);
DISPLAY 1.021277 (-2675 4475);
DISPLAY INVISIBLE (-2675 4475);
FORCEADD UNIVERSAL_POWER..1
(-2725 4500);
FORCEPROP 3 LASTPIN (-2725 4450) SIG_NAME PVCCD_HV_CPU0\g
J 0
(-2715 4460);
DISPLAY 0.659574 (-2715 4460);
PAINT MONO (-2715 4460);
DISPLAY INVISIBLE (-2715 4460);
FORCEPROP 1 LAST HDL_POWER PVCCD_HV_CPU0
J 1
(-2725 4550);
DISPLAY 0.872340 (-2725 4550);
PAINT GREEN (-2725 4550);
FORCEPROP 2 LAST CDS_LIB logical_power
J 0
(-2725 4500);
PAINT MONO (-2725 4500);
DISPLAY INVISIBLE (-2725 4500);
FORCEPROP 1 LAST PATH I122
J 0
(-2675 4525);
DISPLAY 0.872340 (-2675 4525);
PAINT AQUA (-2675 4525);
DISPLAY INVISIBLE (-2675 4525);
FORCEADD Q_RES..2
(-2725 2750);
FORCEPROP 1 LAST PART_NUMBER CS21002FB06
J 0
(-2685 2625);
DISPLAY 0.638298 (-2685 2625);
DISPLAY INVISIBLE (-2685 2625);
FORCEPROP 1 LAST PACK_TYPE 0402LF
J 0
(-2685 2575);
DISPLAY 0.638298 (-2685 2575);
FORCEPROP 1 LAST VALUE 1K
J 0
(-2680 2825);
DISPLAY 0.638298 (-2680 2825);
FORCEPROP 1 LAST TOLERANCE 1%
J 0
(-2680 2775);
DISPLAY 0.638298 (-2680 2775);
FORCEPROP 1 LAST WATTAGE 1/16W
J 0
(-2685 2725);
DISPLAY 0.638298 (-2685 2725);
FORCEPROP 1 LAST MATERIAL CHIP
J 0
(-2685 2675);
DISPLAY 0.638298 (-2685 2675);
FORCEPROP 1 LAST $LOCATION R842
J 0
(-2680 2875);
DISPLAY 0.978723 (-2680 2875);
FORCEPROP 1 LASTPIN (-2725 2850) $PN 1
J 0
(-2720 2812);
DISPLAY 0.787234 (-2720 2812);
FORCEPROP 1 LASTPIN (-2725 2650) $PN 2
J 0
(-2720 2660);
DISPLAY 0.787234 (-2720 2660);
FORCEPROP 2 LAST CDS_LIB pure_quanta
J 0
(-2725 2750);
PAINT MONO (-2725 2750);
DISPLAY INVISIBLE (-2725 2750);
FORCEPROP 1 LAST PATH I123
J 0
(-2675 2925);
DISPLAY 0.978723 (-2675 2925);
PAINT WHITE (-2675 2925);
DISPLAY INVISIBLE (-2675 2925);
FORCEPROP 1 LAST $LOCATION R842
J 0
(-2675 2975);
DISPLAY 1.021277 (-2675 2975);
DISPLAY INVISIBLE (-2675 2975);
FORCEPROP 2 LAST CDS_LOCATION R842
J 0
(-2675 2975);
DISPLAY 1.021277 (-2675 2975);
DISPLAY INVISIBLE (-2675 2975);
FORCEPROP 2 LAST $SEC 1
J 0
(-2675 2975);
DISPLAY 0.680851 (-2675 2975);
PAINT MONO (-2675 2975);
DISPLAY INVISIBLE (-2675 2975);
FORCEPROP 2 LAST CDS_SEC 1
J 0
(-2675 2975);
DISPLAY 1.021277 (-2675 2975);
DISPLAY INVISIBLE (-2675 2975);
FORCEADD UNIVERSAL_POWER..1
(-2725 3000);
FORCEPROP 3 LASTPIN (-2725 2950) SIG_NAME PVCCD_HV_CPU0\g
J 0
(-2715 2960);
DISPLAY 0.659574 (-2715 2960);
PAINT MONO (-2715 2960);
DISPLAY INVISIBLE (-2715 2960);
FORCEPROP 1 LAST HDL_POWER PVCCD_HV_CPU0
J 1
(-2725 3050);
DISPLAY 0.872340 (-2725 3050);
PAINT GREEN (-2725 3050);
FORCEPROP 2 LAST CDS_LIB logical_power
J 0
(-2725 3000);
PAINT MONO (-2725 3000);
DISPLAY INVISIBLE (-2725 3000);
FORCEPROP 1 LAST PATH I124
J 0
(-2675 3025);
DISPLAY 0.872340 (-2675 3025);
PAINT AQUA (-2675 3025);
DISPLAY INVISIBLE (-2675 3025);
FORCEADD Q_RES..2
(-2725 1225);
FORCEPROP 1 LAST PART_NUMBER CS21002FB06
J 0
(-2685 1100);
DISPLAY 0.638298 (-2685 1100);
DISPLAY INVISIBLE (-2685 1100);
FORCEPROP 1 LAST PACK_TYPE 0402LF
J 0
(-2685 1050);
DISPLAY 0.638298 (-2685 1050);
FORCEPROP 1 LAST VALUE 1K
J 0
(-2680 1300);
DISPLAY 0.638298 (-2680 1300);
FORCEPROP 1 LAST WATTAGE 1/16W
J 0
(-2685 1200);
DISPLAY 0.638298 (-2685 1200);
FORCEPROP 1 LAST MATERIAL CHIP
J 0
(-2685 1150);
DISPLAY 0.638298 (-2685 1150);
FORCEPROP 1 LAST TOLERANCE 1%
J 0
(-2680 1250);
DISPLAY 0.638298 (-2680 1250);
FORCEPROP 1 LAST $LOCATION R839
J 0
(-2680 1350);
DISPLAY 0.978723 (-2680 1350);
FORCEPROP 1 LASTPIN (-2725 1325) $PN 1
J 0
(-2720 1287);
DISPLAY 0.787234 (-2720 1287);
FORCEPROP 1 LASTPIN (-2725 1125) $PN 2
J 0
(-2720 1135);
DISPLAY 0.787234 (-2720 1135);
FORCEPROP 2 LAST CDS_LIB pure_quanta
J 0
(-2725 1225);
PAINT MONO (-2725 1225);
DISPLAY INVISIBLE (-2725 1225);
FORCEPROP 1 LAST PATH I125
J 0
(-2675 1400);
DISPLAY 0.978723 (-2675 1400);
PAINT WHITE (-2675 1400);
DISPLAY INVISIBLE (-2675 1400);
FORCEPROP 1 LAST $LOCATION R839
J 0
(-2675 1450);
DISPLAY 1.021277 (-2675 1450);
DISPLAY INVISIBLE (-2675 1450);
FORCEPROP 2 LAST CDS_LOCATION R839
J 0
(-2675 1450);
DISPLAY 1.021277 (-2675 1450);
DISPLAY INVISIBLE (-2675 1450);
FORCEPROP 2 LAST $SEC 1
J 0
(-2675 1450);
DISPLAY 0.680851 (-2675 1450);
PAINT MONO (-2675 1450);
DISPLAY INVISIBLE (-2675 1450);
FORCEPROP 2 LAST CDS_SEC 1
J 0
(-2675 1450);
DISPLAY 1.021277 (-2675 1450);
DISPLAY INVISIBLE (-2675 1450);
FORCEADD UNIVERSAL_POWER..1
(-2725 1475);
FORCEPROP 3 LASTPIN (-2725 1425) SIG_NAME PVCCD_HV_CPU0\g
J 0
(-2715 1435);
DISPLAY 0.659574 (-2715 1435);
PAINT MONO (-2715 1435);
DISPLAY INVISIBLE (-2715 1435);
FORCEPROP 1 LAST HDL_POWER PVCCD_HV_CPU0
J 1
(-2725 1525);
DISPLAY 0.872340 (-2725 1525);
PAINT GREEN (-2725 1525);
FORCEPROP 2 LAST CDS_LIB logical_power
J 0
(-2725 1475);
PAINT MONO (-2725 1475);
DISPLAY INVISIBLE (-2725 1475);
FORCEPROP 1 LAST PATH I126
J 0
(-2675 1500);
DISPLAY 0.872340 (-2675 1500);
PAINT AQUA (-2675 1500);
DISPLAY INVISIBLE (-2675 1500);
FORCEADD OFFPAGE..1
(-8375 5450);
FORCEPROP 2 LAST $XR1 256 
J 0
(-8777 5450);
DISPLAY 0.638298 (-8777 5450);
PAINT MONO (-8777 5450);
FORCEPROP 2 LAST $XR0 216 
J 0
(-8657 5450);
DISPLAY 0.638298 (-8657 5450);
PAINT MONO (-8657 5450);
FORCEPROP 2 LAST CDS_LIB standard
J 0
(-8375 5450);
PAINT MONO (-8375 5450);
DISPLAY INVISIBLE (-8375 5450);
FORCEPROP 1 LAST OFFPAGE TRUE
J 0
(-8050 5325);
DISPLAY 0.872340 (-8050 5325);
PAINT GREEN (-8050 5325);
DISPLAY INVISIBLE (-8050 5325);
FORCEPROP 1 LAST COMMENT_BODY TRUE
J 0
(-8250 5350);
DISPLAY 0.872340 (-8250 5350);
PAINT GREEN (-8250 5350);
DISPLAY INVISIBLE (-8250 5350);
FORCEPROP 2 LAST PATH I22
J 0
(-8625 5500);
DISPLAY 1.021277 (-8625 5500);
DISPLAY INVISIBLE (-8625 5500);
FORCEADD Q_RES..1
(-4900 5450);
FORCEPROP 1 LAST PART_NUMBER CS00002JB13
J 0
(-5000 5525);
DISPLAY 0.510638 (-5000 5525);
DISPLAY INVISIBLE (-5000 5525);
FORCEPROP 1 LAST MATERIAL CHIP
J 0
(-5000 5575);
DISPLAY 0.510638 (-5000 5575);
FORCEPROP 1 LAST VALUE 0
J 2
(-4750 5450);
DISPLAY 0.638298 (-4750 5450);
FORCEPROP 1 LAST TOLERANCE 5%
J 0
(-4725 5450);
DISPLAY 0.638298 (-4725 5450);
FORCEPROP 1 LAST PACK_TYPE 0402LF
J 0
(-4650 5450);
DISPLAY 0.638298 (-4650 5450);
FORCEPROP 1 LAST WATTAGE 1/16W
J 2
(-4775 5575);
DISPLAY 0.510638 (-4775 5575);
FORCEPROP 1 LAST $LOCATION R836
J 0
(-5100 5450);
DISPLAY 0.638298 (-5100 5450);
FORCEPROP 1 LASTPIN (-5000 5450) $PN 1
J 0
(-4988 5462);
DISPLAY 0.787234 (-4988 5462);
FORCEPROP 1 LASTPIN (-4800 5450) $PN 2
J 0
(-4838 5462);
DISPLAY 0.787234 (-4838 5462);
FORCEPROP 2 LAST CDS_LIB pure_quanta
J 0
(-4900 5450);
PAINT MONO (-4900 5450);
DISPLAY INVISIBLE (-4900 5450);
FORCEPROP 1 LAST PATH I26
J 0
(-4950 5600);
DISPLAY 0.978723 (-4950 5600);
PAINT WHITE (-4950 5600);
DISPLAY INVISIBLE (-4950 5600);
FORCEPROP 1 LAST $LOCATION R836
J 0
(-4950 5650);
DISPLAY 1.021277 (-4950 5650);
DISPLAY INVISIBLE (-4950 5650);
FORCEPROP 2 LAST CDS_LOCATION R836
J 0
(-4950 5650);
DISPLAY 1.021277 (-4950 5650);
DISPLAY INVISIBLE (-4950 5650);
FORCEPROP 2 LAST $SEC 1
J 0
(-4950 5650);
DISPLAY 0.680851 (-4950 5650);
PAINT MONO (-4950 5650);
DISPLAY INVISIBLE (-4950 5650);
FORCEPROP 2 LAST CDS_SEC 1
J 0
(-4950 5650);
DISPLAY 1.021277 (-4950 5650);
DISPLAY INVISIBLE (-4950 5650);
FORCEADD OFFPAGE..2
(-2025 5450);
FORCEPROP 2 LAST $XR3 85 
J 0
(-1566 5450);
DISPLAY 0.638298 (-1566 5450);
PAINT MONO (-1566 5450);
FORCEPROP 2 LAST $XR2 84 
J 0
(-1656 5450);
DISPLAY 0.638298 (-1656 5450);
PAINT MONO (-1656 5450);
FORCEPROP 2 LAST $XR1 83 
J 0
(-1746 5450);
DISPLAY 0.638298 (-1746 5450);
PAINT MONO (-1746 5450);
FORCEPROP 2 LAST $XR0 82 
J 0
(-1836 5450);
DISPLAY 0.638298 (-1836 5450);
PAINT MONO (-1836 5450);
FORCEPROP 2 LAST CDS_LIB standard
J 0
(-2025 5450);
DISPLAY INVISIBLE (-2025 5450);
FORCEPROP 1 LAST OFFPAGE TRUE
J 0
(-1700 5325);
DISPLAY 0.872340 (-1700 5325);
PAINT GREEN (-1700 5325);
DISPLAY INVISIBLE (-1700 5325);
FORCEPROP 1 LAST COMMENT_BODY TRUE
J 0
(-2070 5355);
DISPLAY 0.872340 (-2070 5355);
PAINT GREEN (-2070 5355);
DISPLAY INVISIBLE (-2070 5355);
FORCEPROP 2 LAST PATH I51
J 0
(-1825 5500);
DISPLAY 1.021277 (-1825 5500);
DISPLAY INVISIBLE (-1825 5500);
FORCEADD OFFPAGE..2
(-2000 3925);
FORCEPROP 2 LAST $XR3 89 
J 0
(-1541 3925);
DISPLAY 0.638298 (-1541 3925);
PAINT MONO (-1541 3925);
FORCEPROP 2 LAST $XR2 88 
J 0
(-1631 3925);
DISPLAY 0.638298 (-1631 3925);
PAINT MONO (-1631 3925);
FORCEPROP 2 LAST $XR1 87 
J 0
(-1721 3925);
DISPLAY 0.638298 (-1721 3925);
PAINT MONO (-1721 3925);
FORCEPROP 2 LAST $XR0 86 
J 0
(-1811 3925);
DISPLAY 0.638298 (-1811 3925);
PAINT MONO (-1811 3925);
FORCEPROP 2 LAST CDS_LIB standard
J 0
(-2000 3925);
DISPLAY INVISIBLE (-2000 3925);
FORCEPROP 1 LAST OFFPAGE TRUE
J 0
(-1675 3800);
DISPLAY 0.872340 (-1675 3800);
PAINT GREEN (-1675 3800);
DISPLAY INVISIBLE (-1675 3800);
FORCEPROP 1 LAST COMMENT_BODY TRUE
J 0
(-2045 3830);
DISPLAY 0.872340 (-2045 3830);
PAINT GREEN (-2045 3830);
DISPLAY INVISIBLE (-2045 3830);
FORCEPROP 2 LAST PATH I52
J 0
(-1800 3975);
DISPLAY 1.021277 (-1800 3975);
DISPLAY INVISIBLE (-1800 3975);
FORCEADD Q_RES..1
(-4900 3925);
FORCEPROP 1 LAST PART_NUMBER CS00002JB13
J 0
(-5000 4000);
DISPLAY 0.510638 (-5000 4000);
DISPLAY INVISIBLE (-5000 4000);
FORCEPROP 1 LAST WATTAGE 1/16W
J 2
(-4775 4050);
DISPLAY 0.510638 (-4775 4050);
FORCEPROP 1 LAST MATERIAL CHIP
J 0
(-5000 4050);
DISPLAY 0.510638 (-5000 4050);
FORCEPROP 1 LAST VALUE 0
J 2
(-4750 3925);
DISPLAY 0.638298 (-4750 3925);
FORCEPROP 1 LAST PACK_TYPE 0402LF
J 0
(-4650 3925);
DISPLAY 0.638298 (-4650 3925);
FORCEPROP 1 LAST TOLERANCE 5%
J 0
(-4725 3925);
DISPLAY 0.638298 (-4725 3925);
FORCEPROP 1 LAST $LOCATION R837
J 0
(-5100 3925);
DISPLAY 0.638298 (-5100 3925);
FORCEPROP 1 LASTPIN (-5000 3925) $PN 1
J 0
(-4988 3937);
DISPLAY 0.787234 (-4988 3937);
FORCEPROP 1 LASTPIN (-4800 3925) $PN 2
J 0
(-4838 3937);
DISPLAY 0.787234 (-4838 3937);
FORCEPROP 2 LAST CDS_LIB pure_quanta
J 0
(-4900 3925);
PAINT MONO (-4900 3925);
DISPLAY INVISIBLE (-4900 3925);
FORCEPROP 1 LAST PATH I59
J 0
(-4950 4075);
DISPLAY 0.978723 (-4950 4075);
PAINT WHITE (-4950 4075);
DISPLAY INVISIBLE (-4950 4075);
FORCEPROP 1 LAST $LOCATION R837
J 0
(-4950 4125);
DISPLAY 1.021277 (-4950 4125);
DISPLAY INVISIBLE (-4950 4125);
FORCEPROP 2 LAST CDS_LOCATION R837
J 0
(-4950 4125);
DISPLAY 1.021277 (-4950 4125);
DISPLAY INVISIBLE (-4950 4125);
FORCEPROP 2 LAST $SEC 1
J 0
(-4950 4125);
DISPLAY 0.680851 (-4950 4125);
PAINT MONO (-4950 4125);
DISPLAY INVISIBLE (-4950 4125);
FORCEPROP 2 LAST CDS_SEC 1
J 0
(-4950 4125);
DISPLAY 1.021277 (-4950 4125);
DISPLAY INVISIBLE (-4950 4125);
FORCEADD OFFPAGE..1
(-8375 3925);
FORCEPROP 2 LAST $XR1 256 
J 0
(-8777 3925);
DISPLAY 0.638298 (-8777 3925);
PAINT MONO (-8777 3925);
FORCEPROP 2 LAST $XR0 216 
J 0
(-8657 3925);
DISPLAY 0.638298 (-8657 3925);
PAINT MONO (-8657 3925);
FORCEPROP 2 LAST CDS_LIB standard
J 0
(-8375 3925);
PAINT MONO (-8375 3925);
DISPLAY INVISIBLE (-8375 3925);
FORCEPROP 1 LAST OFFPAGE TRUE
J 0
(-8050 3800);
DISPLAY 0.872340 (-8050 3800);
PAINT GREEN (-8050 3800);
DISPLAY INVISIBLE (-8050 3800);
FORCEPROP 1 LAST COMMENT_BODY TRUE
J 0
(-8250 3825);
DISPLAY 0.872340 (-8250 3825);
PAINT GREEN (-8250 3825);
DISPLAY INVISIBLE (-8250 3825);
FORCEPROP 2 LAST PATH I64
J 0
(-8625 3975);
DISPLAY 1.021277 (-8625 3975);
DISPLAY INVISIBLE (-8625 3975);
FORCEADD OFFPAGE..2
(-2050 2425);
FORCEPROP 2 LAST $XR3 93 
J 0
(-1591 2425);
DISPLAY 0.638298 (-1591 2425);
PAINT MONO (-1591 2425);
FORCEPROP 2 LAST $XR2 92 
J 0
(-1681 2425);
DISPLAY 0.638298 (-1681 2425);
PAINT MONO (-1681 2425);
FORCEPROP 2 LAST $XR1 91 
J 0
(-1771 2425);
DISPLAY 0.638298 (-1771 2425);
PAINT MONO (-1771 2425);
FORCEPROP 2 LAST $XR0 90 
J 0
(-1861 2425);
DISPLAY 0.638298 (-1861 2425);
PAINT MONO (-1861 2425);
FORCEPROP 2 LAST CDS_LIB standard
J 0
(-2050 2425);
DISPLAY INVISIBLE (-2050 2425);
FORCEPROP 1 LAST OFFPAGE TRUE
J 0
(-1725 2300);
DISPLAY 0.872340 (-1725 2300);
PAINT GREEN (-1725 2300);
DISPLAY INVISIBLE (-1725 2300);
FORCEPROP 1 LAST COMMENT_BODY TRUE
J 0
(-2095 2330);
DISPLAY 0.872340 (-2095 2330);
PAINT GREEN (-2095 2330);
DISPLAY INVISIBLE (-2095 2330);
FORCEPROP 2 LAST PATH I65
J 0
(-1850 2475);
DISPLAY 1.021277 (-1850 2475);
DISPLAY INVISIBLE (-1850 2475);
FORCEADD OFFPAGE..2
(-2025 900);
FORCEPROP 2 LAST $XR3 97 
J 0
(-1566 900);
DISPLAY 0.638298 (-1566 900);
PAINT MONO (-1566 900);
FORCEPROP 2 LAST $XR2 96 
J 0
(-1656 900);
DISPLAY 0.638298 (-1656 900);
PAINT MONO (-1656 900);
FORCEPROP 2 LAST $XR1 95 
J 0
(-1746 900);
DISPLAY 0.638298 (-1746 900);
PAINT MONO (-1746 900);
FORCEPROP 2 LAST $XR0 94 
J 0
(-1836 900);
DISPLAY 0.638298 (-1836 900);
PAINT MONO (-1836 900);
FORCEPROP 2 LAST CDS_LIB standard
J 0
(-2025 900);
DISPLAY INVISIBLE (-2025 900);
FORCEPROP 1 LAST OFFPAGE TRUE
J 0
(-1700 775);
DISPLAY 0.872340 (-1700 775);
PAINT GREEN (-1700 775);
DISPLAY INVISIBLE (-1700 775);
FORCEPROP 1 LAST COMMENT_BODY TRUE
J 0
(-2070 805);
DISPLAY 0.872340 (-2070 805);
PAINT GREEN (-2070 805);
DISPLAY INVISIBLE (-2070 805);
FORCEPROP 2 LAST PATH I66
J 0
(-1825 950);
DISPLAY 1.021277 (-1825 950);
DISPLAY INVISIBLE (-1825 950);
FORCEADD Q_RES..1
(-4900 2425);
FORCEPROP 1 LAST PART_NUMBER CS00002JB13
J 0
(-5000 2500);
DISPLAY 0.510638 (-5000 2500);
DISPLAY INVISIBLE (-5000 2500);
FORCEPROP 1 LAST MATERIAL CHIP
J 0
(-5000 2550);
DISPLAY 0.510638 (-5000 2550);
FORCEPROP 1 LAST TOLERANCE 5%
J 0
(-4725 2425);
DISPLAY 0.638298 (-4725 2425);
FORCEPROP 1 LAST VALUE 0
J 2
(-4750 2425);
DISPLAY 0.638298 (-4750 2425);
FORCEPROP 1 LAST PACK_TYPE 0402LF
J 0
(-4650 2425);
DISPLAY 0.638298 (-4650 2425);
FORCEPROP 1 LAST WATTAGE 1/16W
J 2
(-4775 2550);
DISPLAY 0.510638 (-4775 2550);
FORCEPROP 1 LAST $LOCATION R838
J 0
(-5100 2425);
DISPLAY 0.638298 (-5100 2425);
FORCEPROP 1 LASTPIN (-5000 2425) $PN 1
J 0
(-4988 2437);
DISPLAY 0.787234 (-4988 2437);
FORCEPROP 1 LASTPIN (-4800 2425) $PN 2
J 0
(-4838 2437);
DISPLAY 0.787234 (-4838 2437);
FORCEPROP 2 LAST CDS_LIB pure_quanta
J 0
(-4900 2425);
PAINT MONO (-4900 2425);
DISPLAY INVISIBLE (-4900 2425);
FORCEPROP 1 LAST PATH I76
J 0
(-4950 2575);
DISPLAY 0.978723 (-4950 2575);
PAINT WHITE (-4950 2575);
DISPLAY INVISIBLE (-4950 2575);
FORCEPROP 1 LAST $LOCATION R838
J 0
(-4950 2625);
DISPLAY 1.021277 (-4950 2625);
DISPLAY INVISIBLE (-4950 2625);
FORCEPROP 2 LAST CDS_LOCATION R838
J 0
(-4950 2625);
DISPLAY 1.021277 (-4950 2625);
DISPLAY INVISIBLE (-4950 2625);
FORCEPROP 2 LAST $SEC 1
J 0
(-4950 2625);
DISPLAY 0.680851 (-4950 2625);
PAINT MONO (-4950 2625);
DISPLAY INVISIBLE (-4950 2625);
FORCEPROP 2 LAST CDS_SEC 1
J 0
(-4950 2625);
DISPLAY 1.021277 (-4950 2625);
DISPLAY INVISIBLE (-4950 2625);
FORCEADD OFFPAGE..1
(-8375 2425);
FORCEPROP 2 LAST $XR1 256 
J 0
(-8777 2425);
DISPLAY 0.638298 (-8777 2425);
PAINT MONO (-8777 2425);
FORCEPROP 2 LAST $XR0 216 
J 0
(-8657 2425);
DISPLAY 0.638298 (-8657 2425);
PAINT MONO (-8657 2425);
FORCEPROP 2 LAST CDS_LIB standard
J 0
(-8375 2425);
PAINT MONO (-8375 2425);
DISPLAY INVISIBLE (-8375 2425);
FORCEPROP 1 LAST OFFPAGE TRUE
J 0
(-8050 2300);
DISPLAY 0.872340 (-8050 2300);
PAINT GREEN (-8050 2300);
DISPLAY INVISIBLE (-8050 2300);
FORCEPROP 1 LAST COMMENT_BODY TRUE
J 0
(-8250 2325);
DISPLAY 0.872340 (-8250 2325);
PAINT GREEN (-8250 2325);
DISPLAY INVISIBLE (-8250 2325);
FORCEPROP 2 LAST PATH I83
J 0
(-8625 2475);
DISPLAY 1.021277 (-8625 2475);
DISPLAY INVISIBLE (-8625 2475);
FORCEADD Q_RES..1
(-4900 900);
FORCEPROP 1 LAST PART_NUMBER CS00002JB13
J 0
(-5000 975);
DISPLAY 0.510638 (-5000 975);
DISPLAY INVISIBLE (-5000 975);
FORCEPROP 1 LAST PACK_TYPE 0402LF
J 0
(-4650 900);
DISPLAY 0.638298 (-4650 900);
FORCEPROP 1 LAST TOLERANCE 5%
J 0
(-4725 900);
DISPLAY 0.638298 (-4725 900);
FORCEPROP 1 LAST VALUE 0
J 2
(-4750 900);
DISPLAY 0.638298 (-4750 900);
FORCEPROP 1 LAST WATTAGE 1/16W
J 2
(-4775 1025);
DISPLAY 0.510638 (-4775 1025);
FORCEPROP 1 LAST MATERIAL CHIP
J 0
(-5000 1025);
DISPLAY 0.510638 (-5000 1025);
FORCEPROP 1 LAST $LOCATION R835
J 0
(-5100 900);
DISPLAY 0.638298 (-5100 900);
FORCEPROP 1 LASTPIN (-5000 900) $PN 1
J 0
(-4988 912);
DISPLAY 0.787234 (-4988 912);
FORCEPROP 1 LASTPIN (-4800 900) $PN 2
J 0
(-4838 912);
DISPLAY 0.787234 (-4838 912);
FORCEPROP 2 LAST CDS_LIB pure_quanta
J 0
(-4900 900);
PAINT MONO (-4900 900);
DISPLAY INVISIBLE (-4900 900);
FORCEPROP 1 LAST PATH I86
J 0
(-4950 1050);
DISPLAY 0.978723 (-4950 1050);
PAINT WHITE (-4950 1050);
DISPLAY INVISIBLE (-4950 1050);
FORCEPROP 1 LAST $LOCATION R835
J 0
(-4950 1100);
DISPLAY 1.021277 (-4950 1100);
DISPLAY INVISIBLE (-4950 1100);
FORCEPROP 2 LAST CDS_LOCATION R835
J 0
(-4950 1100);
DISPLAY 1.021277 (-4950 1100);
DISPLAY INVISIBLE (-4950 1100);
FORCEPROP 2 LAST $SEC 1
J 0
(-4950 1100);
DISPLAY 0.680851 (-4950 1100);
PAINT MONO (-4950 1100);
DISPLAY INVISIBLE (-4950 1100);
FORCEPROP 2 LAST CDS_SEC 1
J 0
(-4950 1100);
DISPLAY 1.021277 (-4950 1100);
DISPLAY INVISIBLE (-4950 1100);
FORCEADD OFFPAGE..1
(-8375 900);
FORCEPROP 2 LAST $XR1 256 
J 0
(-8777 900);
DISPLAY 0.638298 (-8777 900);
PAINT MONO (-8777 900);
FORCEPROP 2 LAST $XR0 216 
J 0
(-8657 900);
DISPLAY 0.638298 (-8657 900);
PAINT MONO (-8657 900);
FORCEPROP 2 LAST CDS_LIB standard
J 0
(-8375 900);
PAINT MONO (-8375 900);
DISPLAY INVISIBLE (-8375 900);
FORCEPROP 1 LAST OFFPAGE TRUE
J 0
(-8050 775);
DISPLAY 0.872340 (-8050 775);
PAINT GREEN (-8050 775);
DISPLAY INVISIBLE (-8050 775);
FORCEPROP 1 LAST COMMENT_BODY TRUE
J 0
(-8250 800);
DISPLAY 0.872340 (-8250 800);
PAINT GREEN (-8250 800);
DISPLAY INVISIBLE (-8250 800);
FORCEPROP 2 LAST PATH I90
J 0
(-8625 950);
DISPLAY 1.021277 (-8625 950);
DISPLAY INVISIBLE (-8625 950);
FORCEADD Q_CAP..1
R 2
(-7475 5150);
FORCEPROP 1 LAST PART_NUMBER CH5104KEB02
J 2
(-7525 5000);
DISPLAY 0.510638 (-7525 5000);
DISPLAY INVISIBLE (-7525 5000);
FORCEPROP 1 LAST MATERIAL EMPTY
J 2
(-7525 5050);
DISPLAY 0.510638 (-7525 5050);
FORCEPROP 1 LAST VALUE 1UF
J 2
(-7525 5200);
DISPLAY 0.510638 (-7525 5200);
FORCEPROP 1 LAST VOLTAGE 25V
J 2
(-7525 5150);
DISPLAY 0.510638 (-7525 5150);
FORCEPROP 1 LAST PACK_TYPE C0402
J 2
(-7525 4950);
DISPLAY 0.510638 (-7525 4950);
FORCEPROP 1 LAST TOLERANCE 10%
J 2
(-7525 5100);
DISPLAY 0.510638 (-7525 5100);
FORCEPROP 1 LAST $LOCATION C622
J 2
(-7525 5250);
DISPLAY 0.978723 (-7525 5250);
FORCEPROP 1 LASTPIN (-7475 5250) $PN 1
J 2
(-7485 5230);
DISPLAY 0.787234 (-7485 5230);
FORCEPROP 1 LASTPIN (-7475 5050) $PN 2
J 2
(-7485 5030);
DISPLAY 0.787234 (-7485 5030);
FORCEPROP 2 LAST CDS_LIB pure_quanta
J 0
(-7475 5150);
PAINT MONO (-7475 5150);
DISPLAY INVISIBLE (-7475 5150);
FORCEPROP 1 LAST PATH I91
J 2
(-7525 5300);
DISPLAY 0.978723 (-7525 5300);
PAINT WHITE (-7525 5300);
DISPLAY INVISIBLE (-7525 5300);
FORCEPROP 2 LAST CDS_LOCATION C622
J 0
(-7525 5350);
DISPLAY 1.021277 (-7525 5350);
DISPLAY INVISIBLE (-7525 5350);
FORCEPROP 2 LAST $SEC 1
J 0
(-7525 5350);
DISPLAY 0.680851 (-7525 5350);
PAINT MONO (-7525 5350);
DISPLAY INVISIBLE (-7525 5350);
FORCEPROP 2 LAST CDS_SEC 1
J 0
(-7525 5350);
DISPLAY 1.021277 (-7525 5350);
DISPLAY INVISIBLE (-7525 5350);
FORCEADD UNIVERSAL_GND..1
(-7475 4850);
FORCEPROP 3 LASTPIN (-7475 4900) SIG_NAME GND\g
J 0
(-7465 4910);
DISPLAY 0.659574 (-7465 4910);
PAINT MONO (-7465 4910);
DISPLAY INVISIBLE (-7465 4910);
FORCEPROP 2 LAST CDS_LIB logical_power
J 0
(-7475 4850);
PAINT MONO (-7475 4850);
DISPLAY INVISIBLE (-7475 4850);
FORCEPROP 1 LAST HDL_POWER GND
J 1
(-7450 4775);
DISPLAY 0.872340 (-7450 4775);
PAINT GREEN (-7450 4775);
DISPLAY INVISIBLE (-7450 4775);
FORCEPROP 1 LAST PATH I93
J 0
(-7400 4850);
DISPLAY 0.872340 (-7400 4850);
PAINT AQUA (-7400 4850);
DISPLAY INVISIBLE (-7400 4850);
FORCEADD Q_CAP..1
R 2
(-7475 3625);
FORCEPROP 1 LAST PART_NUMBER CH5104KEB02
J 2
(-7525 3475);
DISPLAY 0.510638 (-7525 3475);
DISPLAY INVISIBLE (-7525 3475);
FORCEPROP 1 LAST TOLERANCE 10%
J 2
(-7525 3575);
DISPLAY 0.510638 (-7525 3575);
FORCEPROP 1 LAST PACK_TYPE C0402
J 2
(-7525 3425);
DISPLAY 0.510638 (-7525 3425);
FORCEPROP 1 LAST VALUE 1UF
J 2
(-7525 3675);
DISPLAY 0.510638 (-7525 3675);
FORCEPROP 1 LAST VOLTAGE 25V
J 2
(-7525 3625);
DISPLAY 0.510638 (-7525 3625);
FORCEPROP 1 LAST MATERIAL EMPTY
J 2
(-7525 3525);
DISPLAY 0.510638 (-7525 3525);
FORCEPROP 1 LAST $LOCATION C623
J 2
(-7525 3725);
DISPLAY 0.978723 (-7525 3725);
FORCEPROP 1 LASTPIN (-7475 3725) $PN 1
J 2
(-7485 3705);
DISPLAY 0.787234 (-7485 3705);
FORCEPROP 1 LASTPIN (-7475 3525) $PN 2
J 2
(-7485 3505);
DISPLAY 0.787234 (-7485 3505);
FORCEPROP 2 LAST CDS_LIB pure_quanta
J 0
(-7475 3625);
PAINT MONO (-7475 3625);
DISPLAY INVISIBLE (-7475 3625);
FORCEPROP 1 LAST PATH I94
J 2
(-7525 3775);
DISPLAY 0.978723 (-7525 3775);
PAINT WHITE (-7525 3775);
DISPLAY INVISIBLE (-7525 3775);
FORCEPROP 2 LAST CDS_LOCATION C623
J 0
(-7525 3825);
DISPLAY 1.021277 (-7525 3825);
DISPLAY INVISIBLE (-7525 3825);
FORCEPROP 2 LAST $SEC 1
J 0
(-7525 3825);
DISPLAY 0.680851 (-7525 3825);
PAINT MONO (-7525 3825);
DISPLAY INVISIBLE (-7525 3825);
FORCEPROP 2 LAST CDS_SEC 1
J 0
(-7525 3825);
DISPLAY 1.021277 (-7525 3825);
DISPLAY INVISIBLE (-7525 3825);
FORCEADD UNIVERSAL_GND..1
(-7475 3325);
FORCEPROP 3 LASTPIN (-7475 3375) SIG_NAME GND\g
J 0
(-7465 3385);
DISPLAY 0.659574 (-7465 3385);
PAINT MONO (-7465 3385);
DISPLAY INVISIBLE (-7465 3385);
FORCEPROP 2 LAST CDS_LIB logical_power
J 0
(-7475 3325);
PAINT MONO (-7475 3325);
DISPLAY INVISIBLE (-7475 3325);
FORCEPROP 1 LAST HDL_POWER GND
J 1
(-7450 3250);
DISPLAY 0.872340 (-7450 3250);
PAINT GREEN (-7450 3250);
DISPLAY INVISIBLE (-7450 3250);
FORCEPROP 1 LAST PATH I96
J 0
(-7400 3325);
DISPLAY 0.872340 (-7400 3325);
PAINT AQUA (-7400 3325);
DISPLAY INVISIBLE (-7400 3325);
FORCEADD UNIVERSAL_GND..1
(-7475 1825);
FORCEPROP 3 LASTPIN (-7475 1875) SIG_NAME GND\g
J 0
(-7465 1885);
DISPLAY 0.659574 (-7465 1885);
PAINT MONO (-7465 1885);
DISPLAY INVISIBLE (-7465 1885);
FORCEPROP 2 LAST CDS_LIB logical_power
J 0
(-7475 1825);
PAINT MONO (-7475 1825);
DISPLAY INVISIBLE (-7475 1825);
FORCEPROP 1 LAST HDL_POWER GND
J 1
(-7450 1750);
DISPLAY 0.872340 (-7450 1750);
PAINT GREEN (-7450 1750);
DISPLAY INVISIBLE (-7450 1750);
FORCEPROP 1 LAST PATH I97
J 0
(-7400 1825);
DISPLAY 0.872340 (-7400 1825);
PAINT AQUA (-7400 1825);
DISPLAY INVISIBLE (-7400 1825);
FORCEADD Q_CAP..1
R 2
(-7475 2125);
FORCEPROP 1 LAST PART_NUMBER CH5104KEB02
J 2
(-7525 1975);
DISPLAY 0.510638 (-7525 1975);
DISPLAY INVISIBLE (-7525 1975);
FORCEPROP 1 LAST MATERIAL EMPTY
J 2
(-7525 2025);
DISPLAY 0.510638 (-7525 2025);
FORCEPROP 1 LAST PACK_TYPE C0402
J 2
(-7525 1925);
DISPLAY 0.510638 (-7525 1925);
FORCEPROP 1 LAST TOLERANCE 10%
J 2
(-7525 2075);
DISPLAY 0.510638 (-7525 2075);
FORCEPROP 1 LAST VOLTAGE 25V
J 2
(-7525 2125);
DISPLAY 0.510638 (-7525 2125);
FORCEPROP 1 LAST VALUE 1UF
J 2
(-7525 2175);
DISPLAY 0.510638 (-7525 2175);
FORCEPROP 1 LAST $LOCATION C624
J 2
(-7525 2225);
DISPLAY 0.978723 (-7525 2225);
FORCEPROP 1 LASTPIN (-7475 2225) $PN 1
J 2
(-7485 2205);
DISPLAY 0.787234 (-7485 2205);
FORCEPROP 1 LASTPIN (-7475 2025) $PN 2
J 2
(-7485 2005);
DISPLAY 0.787234 (-7485 2005);
FORCEPROP 2 LAST CDS_LIB pure_quanta
J 0
(-7475 2125);
PAINT MONO (-7475 2125);
DISPLAY INVISIBLE (-7475 2125);
FORCEPROP 1 LAST PATH I99
J 2
(-7525 2275);
DISPLAY 0.978723 (-7525 2275);
PAINT WHITE (-7525 2275);
DISPLAY INVISIBLE (-7525 2275);
FORCEPROP 2 LAST CDS_LOCATION C624
J 0
(-7525 2325);
DISPLAY 1.021277 (-7525 2325);
DISPLAY INVISIBLE (-7525 2325);
FORCEPROP 2 LAST $SEC 1
J 0
(-7525 2325);
DISPLAY 0.680851 (-7525 2325);
PAINT MONO (-7525 2325);
DISPLAY INVISIBLE (-7525 2325);
FORCEPROP 2 LAST CDS_SEC 1
J 0
(-7525 2325);
DISPLAY 1.021277 (-7525 2325);
DISPLAY INVISIBLE (-7525 2325);
FORCEADD QUANTA_TITLE_BLOCK_C..1
(-225 -50);
FORCEPROP 0 LAST CDS_CON_LAST_MODIFIED Fri Aug 25 14:01:49 2023
J 0
(-2110 -35);
PAINT MONO (-2110 -35);
DISPLAY INVISIBLE (-2110 -35);
FORCEPROP 2 LAST CUSTOM_TXT_CDS <XR_PAGE_TITLE>
J 0
(-8115 5200);
DISPLAY 0.638298 (-8115 5200);
PAINT PINK (-8115 5200);
DISPLAY INVISIBLE (-8115 5200);
FORCEPROP 2 LAST CUSTOM_TXT_CDS <CON_LAST_MODIFIED>
J 0
(-2110 -35);
DISPLAY 0.978723 (-2110 -35);
FORCEPROP 2 LAST CUSTOM_TXT_CDS <Q_NUMBER>
J 0
(-1628 53);
DISPLAY 1.212766 (-1628 53);
FORCEPROP 2 LAST CUSTOM_TXT_CDS <CON_PAGE_NUM> OF <CON_TOTAL_PAGES>
J 0
(-671 -32);
DISPLAY 0.978723 (-671 -32);
FORCEPROP 2 LAST CUSTOM_TXT_CDS <NAME_1>
J 0
(-3400 125);
FORCEPROP 2 LAST CUSTOM_TXT_CDS <NAME_2>
J 0
(-3400 0);
FORCEPROP 2 LAST CUSTOM_TXT_CDS <Q_PROJ>
J 0
(-2607 52);
DISPLAY 1.212766 (-2607 52);
FORCEPROP 2 LAST CUSTOM_TXT_CDS <Q_REV>
J 0
(-409 53);
DISPLAY 1.212766 (-409 53);
FORCEPROP 1 LAST Q_TITLE SPR CPU0 - DDR RESET PLD TO DIMM
J 0
(-9491 -24);
DISPLAY 2.446809 (-9491 -24);
PAINT GREEN (-9491 -24);
FORCEPROP 1 LAST Q_DEPT 
J 1
(-3988 -1);
DISPLAY 1.957447 (-3988 -1);
PAINT GREEN (-3988 -1);
FORCEPROP 2 LAST CDS_XR_PAGE_TITLE CR-129 : @S9S_MB_2U_LIB.S9S_MB_2U(SCH_1):PAGE129
J 0
(-8115 5200);
DISPLAY 0.638298 (-8115 5200);
PAINT PINK (-8115 5200);
DISPLAY INVISIBLE (-8115 5200);
FORCEPROP 1 LAST COMMENT_BODY TRUE
J 0
(-213 -63);
DISPLAY 0.978723 (-213 -63);
PAINT GREEN (-213 -63);
DISPLAY INVISIBLE (-213 -63);
FORCEPROP 2 LAST PAGE_BORDER TRUE
J 0
(-8115 5200);
DISPLAY 0.638298 (-8115 5200);
PAINT PINK (-8115 5200);
DISPLAY INVISIBLE (-8115 5200);
FORCEPROP 1 LAST CDS_LMAN_SYM_OUTLINE -9475,6775,100,-125
J 0
(-225 -50);
DISPLAY 0.468085 (-225 -50);
PAINT GREEN (-225 -50);
DISPLAY INVISIBLE (-225 -50);
FORCEPROP 2 LAST CDS_LIB pure_quanta
J 0
(-225 -50);
PAINT MONO (-225 -50);
DISPLAY INVISIBLE (-225 -50);
FORCEADD DNS..2
(-7470 595);
PAINT RED (-7470 595);
FORCEPROP 2 LAST CDS_LIB mstr_misc
J 0
(-7470 595);
PAINT MONO (-7470 595);
DISPLAY INVISIBLE (-7470 595);
FORCEPROP 1 LAST COMMENT_BODY TRUE
J 0
(-7470 595);
DISPLAY INVISIBLE (-7470 595);
FORCEADD DNS..2
(-7470 3620);
PAINT RED (-7470 3620);
FORCEPROP 2 LAST CDS_LIB mstr_misc
J 0
(-7470 3620);
PAINT MONO (-7470 3620);
DISPLAY INVISIBLE (-7470 3620);
FORCEPROP 1 LAST COMMENT_BODY TRUE
J 0
(-7470 3620);
DISPLAY INVISIBLE (-7470 3620);
FORCEADD DNS..2
(-7345 3620);
PAINT RED (-7345 3620);
FORCEPROP 2 LAST CDS_LIB mstr_misc
J 0
(-7345 3620);
PAINT MONO (-7345 3620);
DISPLAY INVISIBLE (-7345 3620);
FORCEPROP 1 LAST COMMENT_BODY TRUE
J 0
(-7345 3620);
DISPLAY INVISIBLE (-7345 3620);
FORCEADD DNS..2
(-7470 5145);
PAINT RED (-7470 5145);
FORCEPROP 2 LAST CDS_LIB mstr_misc
J 0
(-7470 5145);
PAINT MONO (-7470 5145);
DISPLAY INVISIBLE (-7470 5145);
FORCEPROP 1 LAST COMMENT_BODY TRUE
J 0
(-7470 5145);
DISPLAY INVISIBLE (-7470 5145);
FORCEADD DNS..2
(-7345 5145);
PAINT RED (-7345 5145);
FORCEPROP 2 LAST CDS_LIB mstr_misc
J 0
(-7345 5145);
PAINT MONO (-7345 5145);
DISPLAY INVISIBLE (-7345 5145);
FORCEPROP 1 LAST COMMENT_BODY TRUE
J 0
(-7345 5145);
DISPLAY INVISIBLE (-7345 5145);
FORCEADD DNS..2
(-7345 2120);
PAINT RED (-7345 2120);
FORCEPROP 2 LAST CDS_LIB mstr_misc
J 0
(-7345 2120);
PAINT MONO (-7345 2120);
DISPLAY INVISIBLE (-7345 2120);
FORCEPROP 1 LAST COMMENT_BODY TRUE
J 0
(-7345 2120);
DISPLAY INVISIBLE (-7345 2120);
FORCEADD DNS..2
(-7345 595);
PAINT RED (-7345 595);
FORCEPROP 2 LAST CDS_LIB mstr_misc
J 0
(-7345 595);
PAINT MONO (-7345 595);
DISPLAY INVISIBLE (-7345 595);
FORCEPROP 1 LAST COMMENT_BODY TRUE
J 0
(-7345 595);
DISPLAY INVISIBLE (-7345 595);
FORCEADD DNS..2
(-7470 2120);
PAINT RED (-7470 2120);
FORCEPROP 2 LAST CDS_LIB mstr_misc
J 0
(-7470 2120);
PAINT MONO (-7470 2120);
DISPLAY INVISIBLE (-7470 2120);
FORCEPROP 1 LAST COMMENT_BODY TRUE
J 0
(-7470 2120);
DISPLAY INVISIBLE (-7470 2120);
WIRE 16 -1 (-2725 1425)(-2725 1325);
WIRE 16 -1 (-2725 2950)(-2725 2850);
WIRE 16 -1 (-2725 4450)(-2725 4350);
WIRE 16 -1 (-2725 5975)(-2725 5875);
WIRE 16 -1 (-7475 1950)(-7475 1875);
WIRE 16 -1 (-7350 1950)(-7475 1950);
WIRE 16 -1 (-7475 2025)(-7475 1950);
WIRE 16 -1 (-7475 3450)(-7475 3375);
WIRE 16 -1 (-7350 3450)(-7475 3450);
WIRE 16 -1 (-7475 3525)(-7475 3450);
WIRE 16 -1 (-7475 4975)(-7475 4900);
WIRE 16 -1 (-7350 4975)(-7475 4975);
WIRE 16 -1 (-7475 5050)(-7475 4975);
WIRE 16 -1 (-7475 425)(-7475 350);
WIRE 16 -1 (-7350 425)(-7475 425);
WIRE 16 -1 (-7475 500)(-7475 425);
WIRE 16 -1 (-2725 900)(-2075 900);
FORCEPROP 2 LAST SIG_NAME RST_M_GH_CPU0_FPGA_N
J 0
(-2650 910);
DISPLAY 0.553191 (-2650 910);
PAINT WHITE (-2650 910);
WIRE 16 -1 (-2725 1125)(-2725 900);
WIRE 16 -1 (-4800 900)(-2725 900);
WIRE 16 -1 (-2725 2650)(-2725 2425);
WIRE 16 -1 (-2725 2425)(-2100 2425);
FORCEPROP 2 LAST SIG_NAME RST_M_EF_CPU0_FPGA_N
J 0
(-2650 2435);
DISPLAY 0.553191 (-2650 2435);
PAINT WHITE (-2650 2435);
WIRE 16 -1 (-4800 2425)(-2725 2425);
WIRE 16 -1 (-7350 3525)(-7350 3450);
WIRE 16 -1 (-7475 5450)(-8325 5450);
FORCEPROP 2 LAST SIG_NAME RST_PLD_CPU0_DRAM_AB_N
J 0
(-8260 5460);
DISPLAY 0.553191 (-8260 5460);
PAINT WHITE (-8260 5460);
WIRE 16 -1 (-7475 5250)(-7475 5450);
WIRE 16 -1 (-7350 5450)(-7475 5450);
WIRE 16 -1 (-7350 5250)(-7350 5450);
WIRE 16 -1 (-5000 5450)(-7350 5450);
WIRE 16 -1 (-2725 5450)(-4800 5450);
WIRE 16 -1 (-2725 5675)(-2725 5450);
WIRE 16 -1 (-2725 5450)(-2075 5450);
FORCEPROP 2 LAST SIG_NAME RST_M_AB_CPU0_FPGA_N
J 0
(-2650 5460);
DISPLAY 0.553191 (-2650 5460);
PAINT WHITE (-2650 5460);
WIRE 16 -1 (-2725 3925)(-2050 3925);
FORCEPROP 2 LAST SIG_NAME RST_M_CD_CPU0_FPGA_N
J 0
(-2625 3935);
DISPLAY 0.553191 (-2625 3935);
PAINT WHITE (-2625 3935);
WIRE 16 -1 (-2725 4150)(-2725 3925);
WIRE 16 -1 (-4800 3925)(-2725 3925);
WIRE 16 -1 (-7475 900)(-8325 900);
FORCEPROP 2 LAST SIG_NAME RST_PLD_CPU0_DRAM_GH_N
J 0
(-8260 910);
DISPLAY 0.553191 (-8260 910);
PAINT WHITE (-8260 910);
WIRE 16 -1 (-7475 700)(-7475 900);
WIRE 16 -1 (-7350 900)(-7475 900);
WIRE 16 -1 (-7350 700)(-7350 900);
WIRE 16 -1 (-5000 900)(-7350 900);
WIRE 16 -1 (-7475 2425)(-8325 2425);
FORCEPROP 2 LAST SIG_NAME RST_PLD_CPU0_DRAM_EF_N
J 0
(-8260 2435);
DISPLAY 0.553191 (-8260 2435);
PAINT WHITE (-8260 2435);
WIRE 16 -1 (-7475 2225)(-7475 2425);
WIRE 16 -1 (-7350 2425)(-7475 2425);
WIRE 16 -1 (-7350 2225)(-7350 2425);
WIRE 16 -1 (-5000 2425)(-7350 2425);
WIRE 16 -1 (-7475 3925)(-8325 3925);
FORCEPROP 2 LAST SIG_NAME RST_PLD_CPU0_DRAM_CD_N
J 0
(-8260 3935);
DISPLAY 0.553191 (-8260 3935);
PAINT WHITE (-8260 3935);
WIRE 16 -1 (-7475 3725)(-7475 3925);
WIRE 16 -1 (-7350 3925)(-7475 3925);
WIRE 16 -1 (-7350 3725)(-7350 3925);
WIRE 16 -1 (-5000 3925)(-7350 3925);
WIRE 16 -1 (-7350 5050)(-7350 4975);
WIRE 16 -1 (-7350 500)(-7350 425);
WIRE 16 -1 (-7350 2025)(-7350 1950);
DOT 1 (-2725 5450);
DOT 1 (-2725 3925);
DOT 1 (-2725 2425);
DOT 1 (-2725 900);
DOT 1 (-7475 2425);
DOT 1 (-7350 2425);
DOT 1 (-7475 3450);
DOT 1 (-7475 3925);
DOT 1 (-7350 3925);
DOT 1 (-7475 4975);
DOT 1 (-7475 5450);
DOT 1 (-7350 5450);
DOT 1 (-7350 900);
DOT 1 (-7475 900);
DOT 1 (-7475 425);
DOT 1 (-7475 1950);
FORCENOTE
20210907 MODIFY FOR GT
(-9450 6300) 0;
DISPLAY LEFT (-9450 6300);
DISPLAY 2.510638 (-9450 6300);
PAINT PINK (-9450 6300);
QUIT
